# BASEBOARD_FAB2 (Tioga Pass) — schematic netlist excerpt (pin names and nets, part order shuffled) for the footprints in the layout excerpt that follows; sources: Cadence DE-HDL packaged netlist, KiCad conversion of Wiwynn_Tioga_Pass_MB.brd

J1A2  SCONN288_H44441004  SCONN  pkg PIP  page 85
  \12v\(1)  = P12V_NVDIMM_KLM
  VSS(93)  = GND
  DQ(4)  = M_L_DQ<5>
  VSS(92)  = GND
  DQ(0)  = M_L_DQ<1>
  VSS(91)  = GND
  DQS9P  = M_L_DQS_DP<9>
  DQS9N  = M_L_DQS_DN<9>
  VSS(90)  = GND
  DQ(6)  = M_L_DQ<7>
  VSS(89)  = GND
  DQ(2)  = M_L_DQ<3>
  VSS(88)  = GND
  DQ(12)  = M_L_DQ<13>
  VSS(87)  = GND
  DQ(8)  = M_L_DQ<9>
  VSS(86)  = GND
  DQS10P  = M_L_DQS_DP<10>
  DQS10N  = M_L_DQS_DN<10>
  VSS(85)  = GND
  DQ(14)  = M_L_DQ<15>
  VSS(84)  = GND
  DQ(10)  = M_L_DQ<11>
  VSS(83)  = GND
  DQ(20)  = M_L_DQ<21>
  VSS(82)  = GND
  DQ(16)  = M_L_DQ<17>
  VSS(81)  = GND
  DQS11P  = M_L_DQS_DP<11>
  DQS11N  = M_L_DQS_DN<11>
  VSS(80)  = GND
  DQ(22)  = M_L_DQ<23>
  VSS(79)  = GND
  DQ(18)  = M_L_DQ<19>
  VSS(78)  = GND
  DQ(28)  = M_L_DQ<29>
  VSS(77)  = GND
  DQ(24)  = M_L_DQ<25>
  VSS(76)  = GND
  DQS12P  = M_L_DQS_DP<12>
  DQS12N  = M_L_DQS_DN<12>
  VSS(75)  = GND
  DQ(30)  = M_L_DQ<31>
  VSS(74)  = GND
  DQ(26)  = M_L_DQ<27>
  VSS(73)  = GND
  CB(4)  = M_L_ECC<5>
  VSS(72)  = GND
  CB(0)  = M_L_ECC<1>
  VSS(71)  = GND
  DQS17P  = M_L_DQS_DP<17>
  DQS17N  = M_L_DQS_DN<17>
  VSS(70)  = GND
  CB(6)  = M_L_ECC<7>
  VSS(69)  = GND
  CB(2)  = M_L_ECC<3>
  VSS(68)  = GND
  RESET_N  = M_KLM_RST_N
  VDD(25)  = PVDDQ_KLM
  CKE(0)  = M_L_CKE<0>
  VDD(24)  = PVDDQ_KLM
  ACT_N  = M_L_ACT_N
  BG(0)  = M_L_BG<0>
  VDD(23)  = PVDDQ_KLM
  A12  = M_L_MA<12>
  A9  = M_L_MA<9>
  VDD(22)  = PVDDQ_KLM
  A8  = M_L_MA<8>
  A6  = M_L_MA<6>
  VDD(21)  = PVDDQ_KLM
  A3  = M_L_MA<3>
  A1  = M_L_MA<1>
  VDD(20)  = PVDDQ_KLM
  CK0P  = M_L_CLK_DP<0>
  CK0N  = M_L_CLK_DN<0>
  VDD(19)  = PVDDQ_KLM
  VTT(1)  = PVTT_KLM
  EVENT_N  = FM_DIMM_EVENT_COD_N
  A0  = M_L_MA<0>
  VDD(18)  = PVDDQ_KLM
  BA(0)  = M_L_BA<0>
  A16_RAS_N  = M_L_MA<16>
  VDD(17)  = PVDDQ_KLM
  S0_N  = M_L_CS_N<0>
  VDD(16)  = PVDDQ_KLM
  A15_CAS_N  = M_L_MA<15>
  ODT(0)  = M_L_ODT<0>
  VDD(15)  = PVDDQ_KLM
  S1_N  = M_L_CS_N<1>
  VDD(14)  = PVDDQ_KLM
  ODT(1)  = M_L_ODT<1>
  VDD(13)  = PVDDQ_KLM
  S2_N_C(0)  = M_L_CS_N<2>
  VSS(67)  = GND
  DQ(36)  = M_L_DQ<37>
  VSS(66)  = GND
  DQ(32)  = M_L_DQ<33>
  VSS(65)  = GND
  DQS13P  = M_L_DQS_DP<13>
  DQS13N  = M_L_DQS_DN<13>
  VSS(64)  = GND
  DQ(38)  = M_L_DQ<39>
  VSS(63)  = GND
  DQ(34)  = M_L_DQ<35>
  VSS(62)  = GND
  DQ(44)  = M_L_DQ<45>
  VSS(61)  = GND
  DQ(40)  = M_L_DQ<41>
  VSS(60)  = GND
  DQS14P  = M_L_DQS_DP<14>
  DQS14N  = M_L_DQS_DN<14>
  VSS(59)  = GND
  DQ(46)  = M_L_DQ<47>
  VSS(58)  = GND
  DQ(42)  = M_L_DQ<43>
  VSS(57)  = GND
  DQ(52)  = M_L_DQ<53>
  VSS(56)  = GND
  DQ(48)  = M_L_DQ<49>
  VSS(55)  = GND
  DQS15P  = M_L_DQS_DP<15>
  DQS15N  = M_L_DQS_DN<15>
  VSS(54)  = GND
  DQ(54)  = M_L_DQ<55>
  VSS(53)  = GND
  DQ(50)  = M_L_DQ<51>
  VSS(52)  = GND
  DQ(60)  = M_L_DQ<61>
  VSS(51)  = GND
  DQ(56)  = M_L_DQ<57>
  VSS(50)  = GND
  DQS16P  = M_L_DQS_DP<16>
  DQS16N  = M_L_DQS_DN<16>
  VSS(49)  = GND
  DQ(62)  = M_L_DQ<63>
  VSS(48)  = GND
  DQ(58)  = M_L_DQ<59>
  VSS(47)  = GND
  SA(0)  = GND
  SA(1)  = PVPP_KLM
  SCL  = SMB_DDR_KLM_VPP_SCL
  VPP(4)  = PVPP_KLM
  VPP(3)  = PVPP_KLM
  RFU(2)  = TP_CH_L_DIMM_L0_RFU_2
  \12v\(0)  = P12V_NVDIMM_KLM
  VREFCA  = M_L_VREF
  VSS(46)  = GND
  DQ(5)  = M_L_DQ<4>
  VSS(45)  = GND
  DQ(1)  = M_L_DQ<0>
  VSS(44)  = GND
  DQS0N  = M_L_DQS_DN<0>
  DQS0P  = M_L_DQS_DP<0>
  VSS(43)  = GND
  DQ(7)  = M_L_DQ<6>
  VSS(42)  = GND
  DQ(3)  = M_L_DQ<2>
  VSS(41)  = GND
  DQ(13)  = M_L_DQ<12>
  VSS(40)  = GND
  DQ(9)  = M_L_DQ<8>
  VSS(39)  = GND
  DQS1N  = M_L_DQS_DN<1>
  DQS1P  = M_L_DQS_DP<1>
  VSS(38)  = GND
  DQ(15)  = M_L_DQ<14>
  VSS(37)  = GND
  DQ(11)  = M_L_DQ<10>
  VSS(36)  = GND
  DQ(21)  = M_L_DQ<20>
  VSS(35)  = GND
  DQ(17)  = M_L_DQ<16>
  VSS(34)  = GND
  DQS2N  = M_L_DQS_DN<2>
  DQS2P  = M_L_DQS_DP<2>
  VSS(33)  = GND
  DQ(23)  = M_L_DQ<22>
  VSS(32)  = GND
  DQ(19)  = M_L_DQ<18>
  VSS(31)  = GND
  DQ(29)  = M_L_DQ<28>
  VSS(30)  = GND
  DQ(25)  = M_L_DQ<24>
  VSS(29)  = GND
  DQS3N  = M_L_DQS_DN<3>
  DQS3P  = M_L_DQS_DP<3>
  VSS(28)  = GND
  DQ(31)  = M_L_DQ<30>
  VSS(27)  = GND
  DQ(27)  = M_L_DQ<26>
  VSS(26)  = GND
  CB(5)  = M_L_ECC<4>
  VSS(25)  = GND
  CB(1)  = M_L_ECC<0>
  VSS(24)  = GND
  DQS8N  = M_L_DQS_DN<8>
  DQS8P  = M_L_DQS_DP<8>
  VSS(23)  = GND
  CB(7)  = M_L_ECC<6>
  VSS(22)  = GND
  CB(3)  = M_L_ECC<2>
  VSS(21)  = GND
  CKE(1)  = M_L_CKE<1>
  VDD(12)  = PVDDQ_KLM
  RFU(0)  = TP_CH_L_DIMM_L0_RFU_0
  VDD(11)  = PVDDQ_KLM
  BG(1)  = M_L_BG<1>
  ALERT_N  = M_L_ALERT_N
  VDD(10)  = PVDDQ_KLM
  A11  = M_L_MA<11>
  A7  = M_L_MA<7>
  VDD(9)  = PVDDQ_KLM
  A5  = M_L_MA<5>
  A4  = M_L_MA<4>
  VDD(8)  = PVDDQ_KLM
  A2  = M_L_MA<2>
  VDD(7)  = PVDDQ_KLM
  CK1P  = M_L_CLK_DP<1>
  CK1N  = M_L_CLK_DN<1>
  VDD(6)  = PVDDQ_KLM
  VTT(0)  = PVTT_KLM
  PAR  = M_L_PAR
  VDD(5)  = PVDDQ_KLM
  BA(1)  = M_L_BA<1>
  A10  = M_L_MA<10>
  VDD(4)  = PVDDQ_KLM
  RFU(1)  = TP_CH_L_DIMM_L0_RFU_1
  A14_WE_N  = M_L_MA<14>
  VDD(3)  = PVDDQ_KLM
  SAVE_N_NC  = FM_ADR_COMPLETE_KLM_N
  VDD(2)  = PVDDQ_KLM
  A13  = M_L_MA<13>
  VDD(1)  = PVDDQ_KLM
  A17  = M_L_MA<17>
  C(2)  = M_L_C<2>
  VDD(0)  = PVDDQ_KLM
  S3_N_C(1)  = M_L_CS_N<3>
  SA(2)  = GND
  VSS(20)  = GND
  DQ(37)  = M_L_DQ<36>
  VSS(19)  = GND
  DQ(33)  = M_L_DQ<32>
  VSS(18)  = GND
  DQS4N  = M_L_DQS_DN<4>
  DQS4P  = M_L_DQS_DP<4>
  VSS(17)  = GND
  DQ(39)  = M_L_DQ<38>
  VSS(16)  = GND
  DQ(35)  = M_L_DQ<34>
  VSS(15)  = GND
  DQ(45)  = M_L_DQ<44>
  VSS(14)  = GND
  DQ(41)  = M_L_DQ<40>
  VSS(13)  = GND
  DQS5N  = M_L_DQS_DN<5>
  DQS5P  = M_L_DQS_DP<5>
  VSS(12)  = GND
  DQ(47)  = M_L_DQ<46>
  VSS(11)  = GND
  DQ(43)  = M_L_DQ<42>
  VSS(10)  = GND
  DQ(53)  = M_L_DQ<52>
  VSS(9)  = GND
  DQ(49)  = M_L_DQ<48>
  VSS(8)  = GND
  DQS6N  = M_L_DQS_DN<6>
  DQS6P  = M_L_DQS_DP<6>
  VSS(7)  = GND
  DQ(55)  = M_L_DQ<54>
  VSS(6)  = GND
  DQ(51)  = M_L_DQ<50>
  VSS(5)  = GND
  DQ(61)  = M_L_DQ<60>
  VSS(4)  = GND
  DQ(57)  = M_L_DQ<56>
  VSS(3)  = GND
  DQS7N  = M_L_DQS_DN<7>
  DQS7P  = M_L_DQS_DP<7>
  VSS(2)  = GND
  DQ(63)  = M_L_DQ<62>
  VSS(1)  = GND
  DQ(59)  = M_L_DQ<58>
  VSS(0)  = GND
  VDDSPD  = PVPP_KLM
  SDA  = SMB_DDR_KLM_VPP_SDA
  VPP(1)  = PVPP_KLM
  VPP(0)  = PVPP_KLM
  VPP(2)  = PVPP_KLM

(kicad_pcb
	(version 20260206)
	(generator "pcbnew")
	(generator_version "10.0")
	(general
		(thickness 1.6)
		(legacy_teardrops no)
	)
	(paper "A4")
	(title_block
		(title "Wiwynn_Tioga_Pass_MB.brd")
		(comment 1 "Tioga Pass / footprint 2031 of 4770 (J1A2), pads 252-291 of 291")
	)
	(layers
		(0 "F.Cu" signal "TOP")
		(4 "In1.Cu" signal "L2GND")
		(6 "In2.Cu" signal "L3")
		(8 "In3.Cu" signal "L4GND")
		(10 "In4.Cu" signal "L5")
		(12 "In5.Cu" signal "L6GND")
		(14 "In6.Cu" signal "L7VCC")
		(16 "In7.Cu" signal "L8VCC")
		(18 "In8.Cu" signal "L9GND")
		(20 "In9.Cu" signal "L10")
		(22 "In10.Cu" signal "L11GND")
		(24 "In11.Cu" signal "L12")
		(26 "In12.Cu" signal "L13GND")
		(2 "B.Cu" signal "BOTTOM")
		(9 "F.Adhes" user "F.Adhesive")
		(11 "B.Adhes" user "B.Adhesive")
		(13 "F.Paste" user "Package Geometry/Pastemask Top")
		(15 "B.Paste" user "Package Geometry/Pastemask Bottom")
		(5 "F.SilkS" user "Ref Des/Silkscreen Top")
		(7 "B.SilkS" user "Ref Des/Silkscreen Bottom")
		(1 "F.Mask" user "Board Geometry/Soldermask Top")
		(3 "B.Mask" user "Board Geometry/Soldermask Bottom")
		(17 "Dwgs.User" user "User.Drawings")
		(19 "Cmts.User" user "User.Comments")
		(21 "Eco1.User" user "User.Eco1")
		(23 "Eco2.User" user "User.Eco2")
		(25 "Edge.Cuts" user "Board Geometry/Outline")
		(27 "Margin" user)
		(31 "F.CrtYd" user "Package Geometry/Place Bound Top")
		(29 "B.CrtYd" user "Package Geometry/Place Bound Bottom")
		(35 "F.Fab" user "Ref Des/Assembly Top")
		(33 "B.Fab" user "Ref Des/Assembly Bottom")
	)
	(footprint ""
		(layer "F.Cu")
		(at 29.699458 -142.6718 90)
		(property "Reference" "J1A2"
			(at -2.623312 42.436542 0)
			(unlocked yes)
			(layer "F.SilkS")
			(effects
				(font
					(size 0.7874 0.5842)
					(thickness 0.1524)
				)
				(justify left)
			)
		)
		(property "Value" ""
			(at 0 0 90)
			(layer "F.Fab")
			(effects
				(font
					(size 1.27 1.27)
				)
			)
		)
		(duplicate_pad_numbers_are_jumpers no)
		(pad "249" smd rect
			(at 4.59994 93.49994 90)
			(size 1.8034 0.508)
			(layers "F.Cu" "F.Mask" "F.Paste")
			(net "M_L_DQ<34>")
		)
		(pad "250" smd rect
			(at 4.59994 94.350078 90)
			(size 1.8034 0.508)
			(layers "F.Cu" "F.Mask" "F.Paste")
			(net "GND")
		)
		(pad "251" smd rect
			(at 4.59994 95.199962 90)
			(size 1.8034 0.508)
			(layers "F.Cu" "F.Mask" "F.Paste")
			(net "M_L_DQ<44>")
		)
		(pad "252" smd rect
			(at 4.59994 96.0501 90)
			(size 1.8034 0.508)
			(layers "F.Cu" "F.Mask" "F.Paste")
			(net "GND")
		)
		(pad "253" smd rect
			(at 4.59994 96.899984 90)
			(size 1.8034 0.508)
			(layers "F.Cu" "F.Mask" "F.Paste")
			(net "M_L_DQ<40>")
		)
		(pad "254" smd rect
			(at 4.59994 97.750122 90)
			(size 1.8034 0.508)
			(layers "F.Cu" "F.Mask" "F.Paste")
			(net "GND")
		)
		(pad "255" smd rect
			(at 4.59994 98.600006 90)
			(size 1.8034 0.508)
			(layers "F.Cu" "F.Mask" "F.Paste")
			(net "M_L_DQS_DN<5>")
		)
		(pad "256" smd rect
			(at 4.59994 99.44989 90)
			(size 1.8034 0.508)
			(layers "F.Cu" "F.Mask" "F.Paste")
			(net "M_L_DQS_DP<5>")
		)
		(pad "257" smd rect
			(at 4.59994 100.300028 90)
			(size 1.8034 0.508)
			(layers "F.Cu" "F.Mask" "F.Paste")
			(net "GND")
		)
		(pad "258" smd rect
			(at 4.59994 101.149912 90)
			(size 1.8034 0.508)
			(layers "F.Cu" "F.Mask" "F.Paste")
			(net "M_L_DQ<46>")
		)
		(pad "259" smd rect
			(at 4.59994 102.00005 90)
			(size 1.8034 0.508)
			(layers "F.Cu" "F.Mask" "F.Paste")
			(net "GND")
		)
		(pad "260" smd rect
			(at 4.59994 102.849934 90)
			(size 1.8034 0.508)
			(layers "F.Cu" "F.Mask" "F.Paste")
			(net "M_L_DQ<42>")
		)
		(pad "261" smd rect
			(at 4.59994 103.700072 90)
			(size 1.8034 0.508)
			(layers "F.Cu" "F.Mask" "F.Paste")
			(net "GND")
		)
		(pad "262" smd rect
			(at 4.59994 104.549956 90)
			(size 1.8034 0.508)
			(layers "F.Cu" "F.Mask" "F.Paste")
			(net "M_L_DQ<52>")
		)
		(pad "263" smd rect
			(at 4.59994 105.400094 90)
			(size 1.8034 0.508)
			(layers "F.Cu" "F.Mask" "F.Paste")
			(net "GND")
		)
		(pad "264" smd rect
			(at 4.59994 106.249978 90)
			(size 1.8034 0.508)
			(layers "F.Cu" "F.Mask" "F.Paste")
			(net "M_L_DQ<48>")
		)
		(pad "265" smd rect
			(at 4.59994 107.100116 90)
			(size 1.8034 0.508)
			(layers "F.Cu" "F.Mask" "F.Paste")
			(net "GND")
		)
		(pad "266" smd rect
			(at 4.59994 107.95 90)
			(size 1.8034 0.508)
			(layers "F.Cu" "F.Mask" "F.Paste")
			(net "M_L_DQS_DN<6>")
		)
		(pad "267" smd rect
			(at 4.59994 108.799884 90)
			(size 1.8034 0.508)
			(layers "F.Cu" "F.Mask" "F.Paste")
			(net "M_L_DQS_DP<6>")
		)
		(pad "268" smd rect
			(at 4.59994 109.650022 90)
			(size 1.8034 0.508)
			(layers "F.Cu" "F.Mask" "F.Paste")
			(net "GND")
		)
		(pad "269" smd rect
			(at 4.59994 110.499906 90)
			(size 1.8034 0.508)
			(layers "F.Cu" "F.Mask" "F.Paste")
			(net "M_L_DQ<54>")
		)
		(pad "270" smd rect
			(at 4.59994 111.350044 90)
			(size 1.8034 0.508)
			(layers "F.Cu" "F.Mask" "F.Paste")
			(net "GND")
		)
		(pad "271" smd rect
			(at 4.59994 112.199928 90)
			(size 1.8034 0.508)
			(layers "F.Cu" "F.Mask" "F.Paste")
			(net "M_L_DQ<50>")
		)
		(pad "272" smd rect
			(at 4.59994 113.050066 90)
			(size 1.8034 0.508)
			(layers "F.Cu" "F.Mask" "F.Paste")
			(net "GND")
		)
		(pad "273" smd rect
			(at 4.59994 113.89995 90)
			(size 1.8034 0.508)
			(layers "F.Cu" "F.Mask" "F.Paste")
			(net "M_L_DQ<60>")
		)
		(pad "274" smd rect
			(at 4.59994 114.750088 90)
			(size 1.8034 0.508)
			(layers "F.Cu" "F.Mask" "F.Paste")
			(net "GND")
		)
		(pad "275" smd rect
			(at 4.59994 115.599972 90)
			(size 1.8034 0.508)
			(layers "F.Cu" "F.Mask" "F.Paste")
			(net "M_L_DQ<56>")
		)
		(pad "276" smd rect
			(at 4.59994 116.45011 90)
			(size 1.8034 0.508)
			(layers "F.Cu" "F.Mask" "F.Paste")
			(net "GND")
		)
		(pad "277" smd rect
			(at 4.59994 117.299994 90)
			(size 1.8034 0.508)
			(layers "F.Cu" "F.Mask" "F.Paste")
			(net "M_L_DQS_DN<7>")
		)
		(pad "278" smd rect
			(at 4.59994 118.149878 90)
			(size 1.8034 0.508)
			(layers "F.Cu" "F.Mask" "F.Paste")
			(net "M_L_DQS_DP<7>")
		)
		(pad "279" smd rect
			(at 4.59994 119.000016 90)
			(size 1.8034 0.508)
			(layers "F.Cu" "F.Mask" "F.Paste")
			(net "GND")
		)
		(pad "280" smd rect
			(at 4.59994 119.8499 90)
			(size 1.8034 0.508)
			(layers "F.Cu" "F.Mask" "F.Paste")
			(net "M_L_DQ<62>")
		)
		(pad "281" smd rect
			(at 4.59994 120.700038 90)
			(size 1.8034 0.508)
			(layers "F.Cu" "F.Mask" "F.Paste")
			(net "GND")
		)
		(pad "282" smd rect
			(at 4.59994 121.549922 90)
			(size 1.8034 0.508)
			(layers "F.Cu" "F.Mask" "F.Paste")
			(net "M_L_DQ<58>")
		)
		(pad "283" smd rect
			(at 4.59994 122.40006 90)
			(size 1.8034 0.508)
			(layers "F.Cu" "F.Mask" "F.Paste")
			(net "GND")
		)
		(pad "284" smd rect
			(at 4.59994 123.249944 90)
			(size 1.8034 0.508)
			(layers "F.Cu" "F.Mask" "F.Paste")
			(net "PVPP_KLM")
		)
		(pad "285" smd rect
			(at 4.59994 124.100082 90)
			(size 1.8034 0.508)
			(layers "F.Cu" "F.Mask" "F.Paste")
			(net "SMB_DDR_KLM_VPP_SDA")
		)
		(pad "286" smd rect
			(at 4.59994 124.949966 90)
			(size 1.8034 0.508)
			(layers "F.Cu" "F.Mask" "F.Paste")
			(net "PVPP_KLM")
		)
		(pad "287" smd rect
			(at 4.59994 125.800104 90)
			(size 1.8034 0.508)
			(layers "F.Cu" "F.Mask" "F.Paste")
			(net "PVPP_KLM")
		)
		(pad "288" smd rect
			(at 4.59994 126.649988 90)
			(size 1.8034 0.508)
			(layers "F.Cu" "F.Mask" "F.Paste")
			(net "PVPP_KLM")
		)
	)
)
